(kicad_pcb
	(version 20260206)
	(generator "pcbnew")
	(generator_version "10.0")
	(general
		(thickness 1.6)
		(legacy_teardrops no)
	)
	(paper "A4")
	(title_block
		(title "04192023_DAF0TMB3IC0_F0TG_MB_C_brd_V02_OCP.brd")
		(comment 1 "Grand Teton / footprints 7718-7725 of 8354")
	)
	(layers
		(0 "F.Cu" signal "TOP")
		(4 "In1.Cu" signal "GND")
		(6 "In2.Cu" signal "IN1")
		(8 "In3.Cu" signal "GND1")
		(10 "In4.Cu" signal "IN2")
		(12 "In5.Cu" signal "GND2")
		(14 "In6.Cu" signal "IN3")
		(16 "In7.Cu" signal "GND3")
		(18 "In8.Cu" signal "VCC")
		(20 "In9.Cu" signal "VCC1")
		(22 "In10.Cu" signal "GND4")
		(24 "In11.Cu" signal "IN4")
		(26 "In12.Cu" signal "GND5")
		(28 "In13.Cu" signal "IN5")
		(30 "In14.Cu" signal "GND6")
		(32 "In15.Cu" signal "IN6")
		(34 "In16.Cu" signal "GND7")
		(2 "B.Cu" signal "BOTTOM")
		(9 "F.Adhes" user "F.Adhesive")
		(11 "B.Adhes" user "B.Adhesive")
		(13 "F.Paste" user "Package Geometry/Pastemask Top")
		(15 "B.Paste" user "Package Geometry/Pastemask Bottom")
		(5 "F.SilkS" user "Ref Des/Silkscreen Top")
		(7 "B.SilkS" user "Ref Des/Silkscreen Bottom")
		(1 "F.Mask" user "Board Geometry/Soldermask Top")
		(3 "B.Mask" user "Board Geometry/Soldermask Bottom")
		(17 "Dwgs.User" user "User.Drawings")
		(19 "Cmts.User" user "User.Comments")
		(21 "Eco1.User" user "User.Eco1")
		(23 "Eco2.User" user "User.Eco2")
		(25 "Edge.Cuts" user "Board Geometry/Outline")
		(27 "Margin" user)
		(31 "F.CrtYd" user "Package Geometry/Place Bound Top")
		(29 "B.CrtYd" user "Package Geometry/Place Bound Bottom")
		(35 "F.Fab" user "Ref Des/Assembly Top")
		(33 "B.Fab" user "Ref Des/Assembly Bottom")
	)
	(footprint ""
		(layer "B.Cu")
		(at 423.668698 -343.961212 -90)
		(property "Reference" "PC223"
			(at 7.654036 -3.431286 270)
			(unlocked yes)
			(layer "B.SilkS")
			(effects
				(font
					(size 0.7874 0.5842)
					(thickness 0.1524)
				)
				(justify left mirror)
			)
		)
		(property "Value" ""
			(at 0 0 90)
			(layer "B.Fab")
			(effects
				(font
					(size 1.27 1.27)
				)
				(justify mirror)
			)
		)
		(duplicate_pad_numbers_are_jumpers no)
		(fp_line
			(start -4.533392 2.249932)
			(end 4.533392 2.249932)
			(stroke
				(width 0.1524)
				(type default)
			)
			(layer "B.SilkS")
		)
		(fp_line
			(start 4.533392 2.249932)
			(end 4.533392 -2.249932)
			(stroke
				(width 0.1524)
				(type default)
			)
			(layer "B.SilkS")
		)
		(fp_line
			(start -4.533392 -2.249932)
			(end -4.533392 2.249932)
			(stroke
				(width 0.1524)
				(type default)
			)
			(layer "B.SilkS")
		)
		(fp_line
			(start 4.533392 -2.249932)
			(end -4.533392 -2.249932)
			(stroke
				(width 0.1524)
				(type default)
			)
			(layer "B.SilkS")
		)
		(fp_rect
			(start 5.39242 2.326132)
			(end 4.533392 -2.326132)
			(stroke
				(width 0)
				(type default)
			)
			(fill yes)
			(layer "B.SilkS")
		)
		(fp_line
			(start -3.750056 2.249932)
			(end 3.750056 2.249932)
			(stroke
				(width 0.1)
				(type default)
			)
			(layer "B.Fab")
		)
		(fp_line
			(start 3.750056 2.249932)
			(end 3.750056 -2.249932)
			(stroke
				(width 0.1)
				(type default)
			)
			(layer "B.Fab")
		)
		(fp_line
			(start -3.750056 -2.249932)
			(end -3.750056 2.249932)
			(stroke
				(width 0.1)
				(type default)
			)
			(layer "B.Fab")
		)
		(fp_line
			(start 3.750056 -2.249932)
			(end -3.750056 -2.249932)
			(stroke
				(width 0.1)
				(type default)
			)
			(layer "B.Fab")
		)
		(fp_text user "+"
			(at 6.322314 0.786384 180)
			(unlocked yes)
			(layer "B.SilkS")
			(effects
				(font
					(size 1.905 1.4224)
					(thickness 0.1524)
				)
				(justify left mirror)
			)
		)
		(fp_text user "-"
			(at -4.8514 -0.14605 270)
			(unlocked yes)
			(layer "B.SilkS")
			(effects
				(font
					(size 1.905 1.4224)
					(thickness 0.1524)
				)
				(justify left mirror)
			)
		)
		(fp_text user "+"
			(at 6.322314 0.786384 180)
			(unlocked yes)
			(layer "B.Fab")
			(effects
				(font
					(size 1.905 1.4224)
					(thickness 0.1524)
				)
				(justify left mirror)
			)
		)
		(fp_text user "-"
			(at -4.8514 -0.14605 270)
			(unlocked yes)
			(layer "B.Fab")
			(effects
				(font
					(size 1.905 1.4224)
					(thickness 0.1524)
				)
				(justify left mirror)
			)
		)
		(pad "1" smd rect
			(at 3.199892 0 90)
			(size 2.413 2.8194)
			(layers "B.Cu" "B.Mask" "B.Paste")
			(net "PVDD11_S3_P0")
		)
		(pad "2" smd rect
			(at -3.199892 0 90)
			(size 2.413 2.8194)
			(layers "B.Cu" "B.Mask" "B.Paste")
			(net "GND")
		)
	)
	(footprint ""
		(layer "B.Cu")
		(at 136.040114 -37.898578)
		(property "Reference" "C6067"
			(at 0 0 0)
			(layer "B.SilkS")
			(hide yes)
			(effects
				(font
					(size 1.27 1.27)
				)
				(justify mirror)
			)
		)
		(property "Value" ""
			(at 0 0 0)
			(layer "B.Fab")
			(effects
				(font
					(size 1.27 1.27)
				)
				(justify mirror)
			)
		)
		(duplicate_pad_numbers_are_jumpers no)
		(fp_line
			(start -0.7874 -0.4064)
			(end -0.7874 0.4064)
			(stroke
				(width 0.1524)
				(type default)
			)
			(layer "B.SilkS")
		)
		(fp_line
			(start -0.7874 0.4064)
			(end 0.7874 0.4064)
			(stroke
				(width 0.1524)
				(type default)
			)
			(layer "B.SilkS")
		)
		(fp_line
			(start 0.7874 -0.4064)
			(end -0.7874 -0.4064)
			(stroke
				(width 0.1524)
				(type default)
			)
			(layer "B.SilkS")
		)
		(fp_line
			(start 0.7874 0.4064)
			(end 0.7874 -0.4064)
			(stroke
				(width 0.1524)
				(type default)
			)
			(layer "B.SilkS")
		)
		(fp_line
			(start -0.67945 -0.3048)
			(end -0.67945 0.3048)
			(stroke
				(width 0.1)
				(type default)
			)
			(layer "B.Fab")
		)
		(fp_line
			(start -0.67945 0.3048)
			(end -0.120396 0.3048)
			(stroke
				(width 0.1)
				(type default)
			)
			(layer "B.Fab")
		)
		(fp_line
			(start -0.12065 -0.3048)
			(end -0.67945 -0.3048)
			(stroke
				(width 0.1)
				(type default)
			)
			(layer "B.Fab")
		)
		(fp_line
			(start -0.12065 -0.2794)
			(end -0.12065 -0.3048)
			(stroke
				(width 0.1)
				(type default)
			)
			(layer "B.Fab")
		)
		(fp_line
			(start -0.120396 0.2794)
			(end 0.12065 0.2794)
			(stroke
				(width 0.1)
				(type default)
			)
			(layer "B.Fab")
		)
		(fp_line
			(start -0.120396 0.3048)
			(end -0.120396 0.2794)
			(stroke
				(width 0.1)
				(type default)
			)
			(layer "B.Fab")
		)
		(fp_line
			(start 0.12065 -0.305054)
			(end 0.12065 -0.2794)
			(stroke
				(width 0.1)
				(type default)
			)
			(layer "B.Fab")
		)
		(fp_line
			(start 0.12065 -0.2794)
			(end -0.12065 -0.2794)
			(stroke
				(width 0.1)
				(type default)
			)
			(layer "B.Fab")
		)
		(fp_line
			(start 0.12065 0.2794)
			(end 0.12065 0.3048)
			(stroke
				(width 0.1)
				(type default)
			)
			(layer "B.Fab")
		)
		(fp_line
			(start 0.12065 0.3048)
			(end 0.67945 0.3048)
			(stroke
				(width 0.1)
				(type default)
			)
			(layer "B.Fab")
		)
		(fp_line
			(start 0.67945 -0.305054)
			(end 0.12065 -0.305054)
			(stroke
				(width 0.1)
				(type default)
			)
			(layer "B.Fab")
		)
		(fp_line
			(start 0.67945 0.3048)
			(end 0.67945 -0.305054)
			(stroke
				(width 0.1)
				(type default)
			)
			(layer "B.Fab")
		)
		(pad "1" smd circle
			(at 0.40005 0 180)
			(size 0 0)
			(layers "B.Cu" "B.Mask" "B.Paste")
			(net "P1V2_AUX")
		)
		(pad "2" smd circle
			(at -0.40005 0 180)
			(size 0 0)
			(layers "B.Cu" "B.Mask" "B.Paste")
			(net "GND")
		)
	)
	(footprint ""
		(layer "B.Cu")
		(at 234.952286 -257.70713 180)
		(property "Reference" ""
			(at 0 0 0)
			(layer "B.SilkS")
			(hide yes)
			(effects
				(font
					(size 1.27 1.27)
				)
				(justify mirror)
			)
		)
		(property "Value" ""
			(at 0 0 0)
			(layer "B.Fab")
			(effects
				(font
					(size 1.27 1.27)
				)
				(justify mirror)
			)
		)
		(duplicate_pad_numbers_are_jumpers no)
		(pad "1" smd circle
			(at 0 0)
			(size 0.9906 0.9906)
			(layers "B.Cu" "B.Mask" "B.Paste")
			(net "Net_46")
		)
		(zone
			(layer "B.Cu")
			(hatch none 0.5)
			(connect_pads
				(clearance 0)
			)
			(min_thickness 0.25)
			(keepout
				(tracks not_allowed)
				(vias allowed)
				(pads allowed)
				(copperpour not_allowed)
				(footprints allowed)
			)
			(placement
				(enabled no)
				(sheetname "")
			)
			(fill
				(thermal_gap 0.5)
				(thermal_bridge_width 0.5)
				(island_removal_mode 0)
			)
			(polygon
				(pts
					(arc
						(start 236.577886 -257.70713)
						(mid 233.326686 -257.70713)
						(end 236.577886 -257.70713)
					)
				)
			)
		)
	)
	(footprint ""
		(layer "B.Cu")
		(at 310.411876 -78.775814 90)
		(property "Reference" "R4605"
			(at 0 0 90)
			(layer "B.SilkS")
			(hide yes)
			(effects
				(font
					(size 1.27 1.27)
				)
				(justify mirror)
			)
		)
		(property "Value" ""
			(at 0 0 90)
			(layer "B.Fab")
			(effects
				(font
					(size 1.27 1.27)
				)
				(justify mirror)
			)
		)
		(duplicate_pad_numbers_are_jumpers no)
		(fp_line
			(start 0.7874 -0.4064)
			(end -0.7874 -0.4064)
			(stroke
				(width 0.1524)
				(type default)
			)
			(layer "B.SilkS")
		)
		(fp_line
			(start -0.7874 -0.4064)
			(end -0.7874 0.4064)
			(stroke
				(width 0.1524)
				(type default)
			)
			(layer "B.SilkS")
		)
		(fp_line
			(start 0.7874 0.4064)
			(end 0.7874 -0.4064)
			(stroke
				(width 0.1524)
				(type default)
			)
			(layer "B.SilkS")
		)
		(fp_line
			(start -0.7874 0.4064)
			(end 0.7874 0.4064)
			(stroke
				(width 0.1524)
				(type default)
			)
			(layer "B.SilkS")
		)
		(fp_line
			(start 0.67945 -0.305054)
			(end 0.12065 -0.305054)
			(stroke
				(width 0.1)
				(type default)
			)
			(layer "B.Fab")
		)
		(fp_line
			(start 0.12065 -0.305054)
			(end 0.12065 -0.2794)
			(stroke
				(width 0.1)
				(type default)
			)
			(layer "B.Fab")
		)
		(fp_line
			(start -0.12065 -0.3048)
			(end -0.67945 -0.3048)
			(stroke
				(width 0.1)
				(type default)
			)
			(layer "B.Fab")
		)
		(fp_line
			(start -0.67945 -0.3048)
			(end -0.67945 0.3048)
			(stroke
				(width 0.1)
				(type default)
			)
			(layer "B.Fab")
		)
		(fp_line
			(start 0.12065 -0.2794)
			(end -0.12065 -0.2794)
			(stroke
				(width 0.1)
				(type default)
			)
			(layer "B.Fab")
		)
		(fp_line
			(start -0.12065 -0.2794)
			(end -0.12065 -0.3048)
			(stroke
				(width 0.1)
				(type default)
			)
			(layer "B.Fab")
		)
		(fp_line
			(start 0.12065 0.2794)
			(end 0.12065 0.3048)
			(stroke
				(width 0.1)
				(type default)
			)
			(layer "B.Fab")
		)
		(fp_line
			(start -0.120396 0.2794)
			(end 0.12065 0.2794)
			(stroke
				(width 0.1)
				(type default)
			)
			(layer "B.Fab")
		)
		(fp_line
			(start 0.67945 0.3048)
			(end 0.67945 -0.305054)
			(stroke
				(width 0.1)
				(type default)
			)
			(layer "B.Fab")
		)
		(fp_line
			(start 0.12065 0.3048)
			(end 0.67945 0.3048)
			(stroke
				(width 0.1)
				(type default)
			)
			(layer "B.Fab")
		)
		(fp_line
			(start -0.120396 0.3048)
			(end -0.120396 0.2794)
			(stroke
				(width 0.1)
				(type default)
			)
			(layer "B.Fab")
		)
		(fp_line
			(start -0.67945 0.3048)
			(end -0.120396 0.3048)
			(stroke
				(width 0.1)
				(type default)
			)
			(layer "B.Fab")
		)
		(pad "1" smd circle
			(at 0.40005 0 270)
			(size 0 0)
			(layers "B.Cu" "B.Mask" "B.Paste")
			(net "P3V3_AUX")
		)
		(pad "2" smd circle
			(at -0.40005 0 270)
			(size 0 0)
			(layers "B.Cu" "B.Mask" "B.Paste")
			(net "PWRGD_PS_PWROK_PLD_ISO")
		)
	)
	(footprint ""
		(layer "B.Cu")
		(at 147.00631 -386.766562 90)
		(property "Reference" "C407"
			(at 0 0 90)
			(layer "B.SilkS")
			(hide yes)
			(effects
				(font
					(size 1.27 1.27)
				)
				(justify mirror)
			)
		)
		(property "Value" ""
			(at 0 0 90)
			(layer "B.Fab")
			(effects
				(font
					(size 1.27 1.27)
				)
				(justify mirror)
			)
		)
		(duplicate_pad_numbers_are_jumpers no)
		(fp_line
			(start 0.299974 -0.150114)
			(end -0.299974 -0.150114)
			(stroke
				(width 0.1)
				(type default)
			)
			(layer "B.Fab")
		)
		(fp_line
			(start -0.299974 -0.150114)
			(end -0.299974 0.150114)
			(stroke
				(width 0.1)
				(type default)
			)
			(layer "B.Fab")
		)
		(fp_line
			(start 0.299974 0.150114)
			(end 0.299974 -0.150114)
			(stroke
				(width 0.1)
				(type default)
			)
			(layer "B.Fab")
		)
		(fp_line
			(start -0.299974 0.150114)
			(end 0.299974 0.150114)
			(stroke
				(width 0.1)
				(type default)
			)
			(layer "B.Fab")
		)
		(pad "1" smd rect
			(at 0.2667 0 270)
			(size 0.3048 0.381)
			(layers "B.Cu" "B.Mask" "B.Paste")
			(net "P0V9_CPU1_RT2_2A")
		)
		(pad "2" smd rect
			(at -0.2667 0 270)
			(size 0.3048 0.381)
			(layers "B.Cu" "B.Mask" "B.Paste")
			(net "GND")
		)
	)
	(footprint ""
		(layer "B.Cu")
		(at 216.916 -342.011 90)
		(property "Reference" "R6753"
			(at 0 0 90)
			(layer "B.SilkS")
			(hide yes)
			(effects
				(font
					(size 1.27 1.27)
				)
				(justify mirror)
			)
		)
		(property "Value" ""
			(at 0 0 90)
			(layer "B.Fab")
			(effects
				(font
					(size 1.27 1.27)
				)
				(justify mirror)
			)
		)
		(duplicate_pad_numbers_are_jumpers no)
		(fp_line
			(start 0.32512 -0.175006)
			(end -0.32512 -0.175006)
			(stroke
				(width 0.1)
				(type default)
			)
			(layer "B.Fab")
		)
		(fp_line
			(start -0.32512 -0.175006)
			(end -0.32512 0.175006)
			(stroke
				(width 0.1)
				(type default)
			)
			(layer "B.Fab")
		)
		(fp_line
			(start 0.32512 0.175006)
			(end 0.32512 -0.175006)
			(stroke
				(width 0.1)
				(type default)
			)
			(layer "B.Fab")
		)
		(fp_line
			(start -0.32512 0.175006)
			(end 0.32512 0.175006)
			(stroke
				(width 0.1)
				(type default)
			)
			(layer "B.Fab")
		)
		(pad "1" smd rect
			(at 0.2667 0 270)
			(size 0.3048 0.381)
			(layers "B.Cu" "B.Mask" "B.Paste")
			(net "P1V8_CPU1_RT_1D")
		)
		(pad "2" smd rect
			(at -0.2667 0 90)
			(size 0.3048 0.381)
			(layers "B.Cu" "B.Mask" "B.Paste")
			(net "SMB_RT_CPU1_P2_R_SCL")
		)
	)
	(footprint ""
		(layer "B.Cu")
		(at 79.906368 -386.766562 90)
		(property "Reference" "C326"
			(at 0 0 90)
			(layer "B.SilkS")
			(hide yes)
			(effects
				(font
					(size 1.27 1.27)
				)
				(justify mirror)
			)
		)
		(property "Value" ""
			(at 0 0 90)
			(layer "B.Fab")
			(effects
				(font
					(size 1.27 1.27)
				)
				(justify mirror)
			)
		)
		(duplicate_pad_numbers_are_jumpers no)
		(fp_line
			(start 0.299974 -0.150114)
			(end -0.299974 -0.150114)
			(stroke
				(width 0.1)
				(type default)
			)
			(layer "B.Fab")
		)
		(fp_line
			(start -0.299974 -0.150114)
			(end -0.299974 0.150114)
			(stroke
				(width 0.1)
				(type default)
			)
			(layer "B.Fab")
		)
		(fp_line
			(start 0.299974 0.150114)
			(end 0.299974 -0.150114)
			(stroke
				(width 0.1)
				(type default)
			)
			(layer "B.Fab")
		)
		(fp_line
			(start -0.299974 0.150114)
			(end 0.299974 0.150114)
			(stroke
				(width 0.1)
				(type default)
			)
			(layer "B.Fab")
		)
		(pad "1" smd rect
			(at 0.2667 0 270)
			(size 0.3048 0.381)
			(layers "B.Cu" "B.Mask" "B.Paste")
			(net "P0V9_CPU1_RT1_2A")
		)
		(pad "2" smd rect
			(at -0.2667 0 270)
			(size 0.3048 0.381)
			(layers "B.Cu" "B.Mask" "B.Paste")
			(net "GND")
		)
	)
	(footprint ""
		(layer "B.Cu")
		(at 183.164734 -399.867882)
		(property "Reference" "PR3932"
			(at 0 0 0)
			(layer "B.SilkS")
			(hide yes)
			(effects
				(font
					(size 1.27 1.27)
				)
				(justify mirror)
			)
		)
		(property "Value" ""
			(at 0 0 0)
			(layer "B.Fab")
			(effects
				(font
					(size 1.27 1.27)
				)
				(justify mirror)
			)
		)
		(duplicate_pad_numbers_are_jumpers no)
		(fp_line
			(start -0.7874 -0.4064)
			(end -0.7874 0.4064)
			(stroke
				(width 0.1524)
				(type default)
			)
			(layer "B.SilkS")
		)
		(fp_line
			(start -0.7874 0.4064)
			(end 0.7874 0.4064)
			(stroke
				(width 0.1524)
				(type default)
			)
			(layer "B.SilkS")
		)
		(fp_line
			(start 0.7874 -0.4064)
			(end -0.7874 -0.4064)
			(stroke
				(width 0.1524)
				(type default)
			)
			(layer "B.SilkS")
		)
		(fp_line
			(start 0.7874 0.4064)
			(end 0.7874 -0.4064)
			(stroke
				(width 0.1524)
				(type default)
			)
			(layer "B.SilkS")
		)
		(fp_line
			(start -0.67945 -0.3048)
			(end -0.67945 0.3048)
			(stroke
				(width 0.1)
				(type default)
			)
			(layer "B.Fab")
		)
		(fp_line
			(start -0.67945 0.3048)
			(end -0.120396 0.3048)
			(stroke
				(width 0.1)
				(type default)
			)
			(layer "B.Fab")
		)
		(fp_line
			(start -0.12065 -0.3048)
			(end -0.67945 -0.3048)
			(stroke
				(width 0.1)
				(type default)
			)
			(layer "B.Fab")
		)
		(fp_line
			(start -0.12065 -0.2794)
			(end -0.12065 -0.3048)
			(stroke
				(width 0.1)
				(type default)
			)
			(layer "B.Fab")
		)
		(fp_line
			(start -0.120396 0.2794)
			(end 0.12065 0.2794)
			(stroke
				(width 0.1)
				(type default)
			)
			(layer "B.Fab")
		)
		(fp_line
			(start -0.120396 0.3048)
			(end -0.120396 0.2794)
			(stroke
				(width 0.1)
				(type default)
			)
			(layer "B.Fab")
		)
		(fp_line
			(start 0.12065 -0.305054)
			(end 0.12065 -0.2794)
			(stroke
				(width 0.1)
				(type default)
			)
			(layer "B.Fab")
		)
		(fp_line
			(start 0.12065 -0.2794)
			(end -0.12065 -0.2794)
			(stroke
				(width 0.1)
				(type default)
			)
			(layer "B.Fab")
		)
		(fp_line
			(start 0.12065 0.2794)
			(end 0.12065 0.3048)
			(stroke
				(width 0.1)
				(type default)
			)
			(layer "B.Fab")
		)
		(fp_line
			(start 0.12065 0.3048)
			(end 0.67945 0.3048)
			(stroke
				(width 0.1)
				(type default)
			)
			(layer "B.Fab")
		)
		(fp_line
			(start 0.67945 -0.305054)
			(end 0.12065 -0.305054)
			(stroke
				(width 0.1)
				(type default)
			)
			(layer "B.Fab")
		)
		(fp_line
			(start 0.67945 0.3048)
			(end 0.67945 -0.305054)
			(stroke
				(width 0.1)
				(type default)
			)
			(layer "B.Fab")
		)
		(pad "1" smd circle
			(at 0.40005 0 180)
			(size 0 0)
			(layers "B.Cu" "B.Mask" "B.Paste")
			(net "HSC_VOSEN")
		)
		(pad "2" smd circle
			(at -0.40005 0 180)
			(size 0 0)
			(layers "B.Cu" "B.Mask" "B.Paste")
			(net "AGND_HSC")
		)
	)
)
